(kicad_pcb
	(version 20260206)
	(generator "pcbnew")
	(generator_version "10.0")
	(general
		(thickness 1.6)
		(legacy_teardrops no)
	)
	(paper "A4")
	(title_block
		(title "dpb — 14545-sa.0730WZS0815.brd")
		(comment 1 "Honey Badger (Wiwynn) / footprints 1044-1051 of 1066")
	)
	(layers
		(0 "F.Cu" signal "TOP")
		(4 "In1.Cu" signal "L2GND")
		(6 "In2.Cu" signal "L3")
		(8 "In3.Cu" signal "L4VCC")
		(10 "In4.Cu" signal "L5VCC")
		(12 "In5.Cu" signal "L6")
		(14 "In6.Cu" signal "L7GND")
		(2 "B.Cu" signal "BOTTOM")
		(9 "F.Adhes" user "F.Adhesive")
		(11 "B.Adhes" user "B.Adhesive")
		(13 "F.Paste" user "Package Geometry/Pastemask Top")
		(15 "B.Paste" user "Package Geometry/Pastemask Bottom")
		(5 "F.SilkS" user "Ref Des/Silkscreen Top")
		(7 "B.SilkS" user "Ref Des/Silkscreen Bottom")
		(1 "F.Mask" user "Board Geometry/Soldermask Top")
		(3 "B.Mask" user "Board Geometry/Soldermask Bottom")
		(17 "Dwgs.User" user "User.Drawings")
		(19 "Cmts.User" user "User.Comments")
		(21 "Eco1.User" user "User.Eco1")
		(23 "Eco2.User" user "User.Eco2")
		(25 "Edge.Cuts" user "Board Geometry/Outline")
		(27 "Margin" user)
		(31 "F.CrtYd" user "Package Geometry/Place Bound Top")
		(29 "B.CrtYd" user "Package Geometry/Place Bound Bottom")
		(35 "F.Fab" user "Ref Des/Assembly Top")
		(33 "B.Fab" user "Ref Des/Assembly Bottom")
	)
	(footprint ""
		(layer "F.Cu")
		(at 242.569746 -11.6967 90)
		(property "Reference" "PC5"
			(at 0 0 90)
			(layer "F.SilkS")
			(hide yes)
			(effects
				(font
					(size 1.27 1.27)
				)
			)
		)
		(property "Value" "SC22U25V5MX-GP"
			(at -0.0762 -6.1214 90)
			(unlocked yes)
			(layer "F.Fab")
			(hide yes)
			(effects
				(font
					(size 1.016 1.016)
					(thickness 0.1524)
				)
			)
		)
		(property "Device Type" "C805H58"
			(at -0.0762 -8.1534 90)
			(unlocked yes)
			(layer "F.Fab")
			(hide yes)
			(effects
				(font
					(size 1.016 1.016)
					(thickness 0.1524)
				)
			)
		)
		(duplicate_pad_numbers_are_jumpers no)
		(fp_line
			(start 0.635 0)
			(end -0.635 0)
			(stroke
				(width 0.508)
				(type default)
			)
			(layer "F.SilkS")
		)
		(fp_rect
			(start -0.9652 1.778)
			(end 0.9652 -1.778)
			(stroke
				(width 0)
				(type default)
			)
			(fill no)
			(layer "F.CrtYd")
		)
		(fp_poly
			(pts
				(xy -0.9652 -1.778) (xy 0.9652 -1.778) (xy 0.9652 1.778) (xy -0.9652 1.778)
			)
			(stroke
				(width 0)
				(type default)
			)
			(fill no)
			(layer "F.Fab")
		)
		(pad "1" smd rect
			(at 0 -0.9652 90)
			(size 1.397 1.143)
			(layers "F.Cu" "F.Mask" "F.Paste")
			(net "P5VA_12VIN")
		)
		(pad "2" smd rect
			(at 0 0.9652 90)
			(size 1.397 1.143)
			(layers "F.Cu" "F.Mask" "F.Paste")
			(net "GND")
		)
	)
	(footprint ""
		(layer "F.Cu")
		(at 57.531 -375.9454 90)
		(property "Reference" "R377"
			(at 0 0 90)
			(layer "F.SilkS")
			(hide yes)
			(effects
				(font
					(size 1.27 1.27)
				)
			)
		)
		(property "Value" "10KR2F-2-GP"
			(at 0.064008 -3.993896 90)
			(unlocked yes)
			(layer "F.Fab")
			(hide yes)
			(effects
				(font
					(size 1.016 1.016)
					(thickness 0.1524)
				)
			)
		)
		(property "Device Type" "R402H16"
			(at 0.064008 -5.517896 90)
			(unlocked yes)
			(layer "F.Fab")
			(hide yes)
			(effects
				(font
					(size 1.016 1.016)
					(thickness 0.1524)
				)
			)
		)
		(duplicate_pad_numbers_are_jumpers no)
		(fp_line
			(start 0.508 -0.9398)
			(end -0.508 -0.9398)
			(stroke
				(width 0.1524)
				(type default)
			)
			(layer "F.SilkS")
		)
		(fp_line
			(start -0.508 -0.9398)
			(end -0.508 0.9398)
			(stroke
				(width 0.1524)
				(type default)
			)
			(layer "F.SilkS")
		)
		(fp_rect
			(start -0.508 0.9398)
			(end 0.508 -0.9398)
			(stroke
				(width 0)
				(type default)
			)
			(fill no)
			(layer "F.CrtYd")
		)
		(fp_rect
			(start -0.508 0.9398)
			(end 0.508 -0.9398)
			(stroke
				(width 0)
				(type default)
			)
			(fill no)
			(layer "F.Fab")
		)
		(pad "1" smd custom
			(at 0 -0.4445 90)
			(size 0.1397 0.1397)
			(layers "F.Cu" "F.Mask" "F.Paste")
			(net "P12V")
			(options
				(clearance outline)
				(anchor circle)
			)
			(primitives
				(gr_poly
					(pts
						(arc
							(start -0.1778 -0.2794)
							(mid -0.249642 -0.249642)
							(end -0.2794 -0.1778)
						)
						(arc
							(start -0.2794 0.1778)
							(mid -0.249642 0.249642)
							(end -0.1778 0.2794)
						)
						(arc
							(start 0.1778 0.2794)
							(mid 0.249642 0.249642)
							(end 0.2794 0.1778)
						)
						(arc
							(start 0.2794 -0.1778)
							(mid 0.249642 -0.249642)
							(end 0.1778 -0.2794)
						)
					)
					(width 0)
					(fill yes)
				)
			)
		)
		(pad "2" smd custom
			(at 0 0.4445 90)
			(size 0.1397 0.1397)
			(layers "F.Cu" "F.Mask" "F.Paste")
			(net "HDD6_LED_G")
			(options
				(clearance outline)
				(anchor circle)
			)
			(primitives
				(gr_poly
					(pts
						(arc
							(start -0.1778 -0.2794)
							(mid -0.249642 -0.249642)
							(end -0.2794 -0.1778)
						)
						(arc
							(start -0.2794 0.1778)
							(mid -0.249642 0.249642)
							(end -0.1778 0.2794)
						)
						(arc
							(start 0.1778 0.2794)
							(mid 0.249642 0.249642)
							(end 0.2794 0.1778)
						)
						(arc
							(start 0.2794 -0.1778)
							(mid 0.249642 -0.249642)
							(end 0.1778 -0.2794)
						)
					)
					(width 0)
					(fill yes)
				)
			)
		)
	)
	(footprint ""
		(layer "F.Cu")
		(at 95.7834 -10.7442 -90)
		(property "Reference" "R480"
			(at 0 0 270)
			(layer "F.SilkS")
			(hide yes)
			(effects
				(font
					(size 1.27 1.27)
				)
			)
		)
		(property "Value" "0R2J-2-GP"
			(at 0.064008 -3.993896 270)
			(unlocked yes)
			(layer "F.Fab")
			(hide yes)
			(effects
				(font
					(size 1.016 1.016)
					(thickness 0.1524)
				)
			)
		)
		(property "Device Type" "R402H16"
			(at 0.064008 -5.517896 270)
			(unlocked yes)
			(layer "F.Fab")
			(hide yes)
			(effects
				(font
					(size 1.016 1.016)
					(thickness 0.1524)
				)
			)
		)
		(duplicate_pad_numbers_are_jumpers no)
		(fp_line
			(start -0.508 -0.9398)
			(end -0.508 0.9398)
			(stroke
				(width 0.1524)
				(type default)
			)
			(layer "F.SilkS")
		)
		(fp_line
			(start 0.508 -0.9398)
			(end -0.508 -0.9398)
			(stroke
				(width 0.1524)
				(type default)
			)
			(layer "F.SilkS")
		)
		(fp_rect
			(start -0.508 0.9398)
			(end 0.508 -0.9398)
			(stroke
				(width 0)
				(type default)
			)
			(fill no)
			(layer "F.CrtYd")
		)
		(fp_rect
			(start -0.508 0.9398)
			(end 0.508 -0.9398)
			(stroke
				(width 0)
				(type default)
			)
			(fill no)
			(layer "F.Fab")
		)
		(pad "1" smd custom
			(at 0 -0.4445 270)
			(size 0.1397 0.1397)
			(layers "F.Cu" "F.Mask" "F.Paste")
			(net "SW_HDD14_G")
			(options
				(clearance outline)
				(anchor circle)
			)
			(primitives
				(gr_poly
					(pts
						(arc
							(start -0.1778 -0.2794)
							(mid -0.249642 -0.249642)
							(end -0.2794 -0.1778)
						)
						(arc
							(start -0.2794 0.1778)
							(mid -0.249642 0.249642)
							(end -0.1778 0.2794)
						)
						(arc
							(start 0.1778 0.2794)
							(mid 0.249642 0.249642)
							(end 0.2794 0.1778)
						)
						(arc
							(start 0.2794 -0.1778)
							(mid 0.249642 -0.249642)
							(end 0.1778 -0.2794)
						)
					)
					(width 0)
					(fill yes)
				)
			)
		)
		(pad "2" smd custom
			(at 0 0.4445 270)
			(size 0.1397 0.1397)
			(layers "F.Cu" "F.Mask" "F.Paste")
			(net "SW_HDD14_R")
			(options
				(clearance outline)
				(anchor circle)
			)
			(primitives
				(gr_poly
					(pts
						(arc
							(start -0.1778 -0.2794)
							(mid -0.249642 -0.249642)
							(end -0.2794 -0.1778)
						)
						(arc
							(start -0.2794 0.1778)
							(mid -0.249642 0.249642)
							(end -0.1778 0.2794)
						)
						(arc
							(start 0.1778 0.2794)
							(mid 0.249642 0.249642)
							(end 0.2794 0.1778)
						)
						(arc
							(start 0.2794 -0.1778)
							(mid 0.249642 -0.249642)
							(end 0.1778 -0.2794)
						)
					)
					(width 0)
					(fill yes)
				)
			)
		)
	)
	(footprint ""
		(layer "F.Cu")
		(at 14.096746 -482.9937 -90)
		(property "Reference" "PC34"
			(at 0 0 270)
			(layer "F.SilkS")
			(hide yes)
			(effects
				(font
					(size 1.27 1.27)
				)
			)
		)
		(property "Value" "SCD1U25V2KX-GP"
			(at 1.1811 -2.7051 270)
			(unlocked yes)
			(layer "F.Fab")
			(hide yes)
			(effects
				(font
					(size 1.016 1.016)
					(thickness 0.1524)
				)
			)
		)
		(property "Device Type" "C402H22"
			(at 1.1811 -4.2291 270)
			(unlocked yes)
			(layer "F.Fab")
			(hide yes)
			(effects
				(font
					(size 1.016 1.016)
					(thickness 0.1524)
				)
			)
		)
		(duplicate_pad_numbers_are_jumpers no)
		(fp_rect
			(start -0.4318 0.9525)
			(end 0.4318 -0.9525)
			(stroke
				(width 0)
				(type default)
			)
			(fill no)
			(layer "F.CrtYd")
		)
		(fp_rect
			(start -0.4318 0.9525)
			(end 0.4318 -0.9525)
			(stroke
				(width 0)
				(type default)
			)
			(fill no)
			(layer "F.Fab")
		)
		(pad "1" smd custom
			(at 0 -0.4445 270)
			(size 0.1524 0.1524)
			(layers "F.Cu" "F.Mask" "F.Paste")
			(net "P5VC")
			(options
				(clearance outline)
				(anchor circle)
			)
			(primitives
				(gr_poly
					(pts
						(arc
							(start 0.3048 -0.2032)
							(mid 0.275042 -0.275042)
							(end 0.2032 -0.3048)
						)
						(arc
							(start -0.2032 -0.3048)
							(mid -0.275042 -0.275042)
							(end -0.3048 -0.2032)
						)
						(arc
							(start -0.3048 0.2032)
							(mid -0.275042 0.275042)
							(end -0.2032 0.3048)
						)
						(arc
							(start 0.2032 0.3048)
							(mid 0.275042 0.275042)
							(end 0.3048 0.2032)
						)
					)
					(width 0)
					(fill yes)
				)
			)
		)
		(pad "2" smd custom
			(at 0 0.4445 270)
			(size 0.1524 0.1524)
			(layers "F.Cu" "F.Mask" "F.Paste")
			(net "P5VC_LL_NET")
			(options
				(clearance outline)
				(anchor circle)
			)
			(primitives
				(gr_poly
					(pts
						(arc
							(start 0.3048 -0.2032)
							(mid 0.275042 -0.275042)
							(end 0.2032 -0.3048)
						)
						(arc
							(start -0.2032 -0.3048)
							(mid -0.275042 -0.275042)
							(end -0.3048 -0.2032)
						)
						(arc
							(start -0.3048 0.2032)
							(mid -0.275042 0.275042)
							(end -0.2032 0.3048)
						)
						(arc
							(start 0.2032 0.3048)
							(mid 0.275042 0.275042)
							(end 0.3048 0.2032)
						)
					)
					(width 0)
					(fill yes)
				)
			)
		)
	)
	(footprint ""
		(layer "F.Cu")
		(at 85.781134 -494.641886 -90)
		(property "Reference" "R444"
			(at 0 0 270)
			(layer "F.SilkS")
			(hide yes)
			(effects
				(font
					(size 1.27 1.27)
				)
			)
		)
		(property "Value" "4K7R2J-2-GP"
			(at 0.064008 -3.993896 270)
			(unlocked yes)
			(layer "F.Fab")
			(hide yes)
			(effects
				(font
					(size 1.016 1.016)
					(thickness 0.1524)
				)
			)
		)
		(property "Device Type" "R402H16"
			(at 0.064008 -5.517896 270)
			(unlocked yes)
			(layer "F.Fab")
			(hide yes)
			(effects
				(font
					(size 1.016 1.016)
					(thickness 0.1524)
				)
			)
		)
		(duplicate_pad_numbers_are_jumpers no)
		(fp_line
			(start -0.508 -0.9398)
			(end -0.508 0.9398)
			(stroke
				(width 0.1524)
				(type default)
			)
			(layer "F.SilkS")
		)
		(fp_line
			(start 0.508 -0.9398)
			(end -0.508 -0.9398)
			(stroke
				(width 0.1524)
				(type default)
			)
			(layer "F.SilkS")
		)
		(fp_rect
			(start -0.508 0.9398)
			(end 0.508 -0.9398)
			(stroke
				(width 0)
				(type default)
			)
			(fill no)
			(layer "F.CrtYd")
		)
		(fp_rect
			(start -0.508 0.9398)
			(end 0.508 -0.9398)
			(stroke
				(width 0)
				(type default)
			)
			(fill no)
			(layer "F.Fab")
		)
		(pad "1" smd custom
			(at 0 -0.4445 270)
			(size 0.1397 0.1397)
			(layers "F.Cu" "F.Mask" "F.Paste")
			(net "P3V3")
			(options
				(clearance outline)
				(anchor circle)
			)
			(primitives
				(gr_poly
					(pts
						(arc
							(start -0.1778 -0.2794)
							(mid -0.249642 -0.249642)
							(end -0.2794 -0.1778)
						)
						(arc
							(start -0.2794 0.1778)
							(mid -0.249642 0.249642)
							(end -0.1778 0.2794)
						)
						(arc
							(start 0.1778 0.2794)
							(mid 0.249642 0.249642)
							(end 0.2794 0.1778)
						)
						(arc
							(start 0.2794 -0.1778)
							(mid 0.249642 -0.249642)
							(end 0.1778 -0.2794)
						)
					)
					(width 0)
					(fill yes)
				)
			)
		)
		(pad "2" smd custom
			(at 0 0.4445 270)
			(size 0.1397 0.1397)
			(layers "F.Cu" "F.Mask" "F.Paste")
			(net "SAS_EXP_A_PWR5")
			(options
				(clearance outline)
				(anchor circle)
			)
			(primitives
				(gr_poly
					(pts
						(arc
							(start -0.1778 -0.2794)
							(mid -0.249642 -0.249642)
							(end -0.2794 -0.1778)
						)
						(arc
							(start -0.2794 0.1778)
							(mid -0.249642 0.249642)
							(end -0.1778 0.2794)
						)
						(arc
							(start 0.1778 0.2794)
							(mid 0.249642 0.249642)
							(end 0.2794 0.1778)
						)
						(arc
							(start 0.2794 -0.1778)
							(mid 0.249642 -0.249642)
							(end 0.1778 -0.2794)
						)
					)
					(width 0)
					(fill yes)
				)
			)
		)
	)
	(footprint ""
		(layer "F.Cu")
		(at 225.9838 -433.4256)
		(property "Reference" "PR55"
			(at 0 0 0)
			(layer "F.SilkS")
			(hide yes)
			(effects
				(font
					(size 1.27 1.27)
				)
			)
		)
		(property "Value" "100KR2F-L1-GP"
			(at 0.064008 -3.993896 0)
			(unlocked yes)
			(layer "F.Fab")
			(hide yes)
			(effects
				(font
					(size 1.016 1.016)
					(thickness 0.1524)
				)
			)
		)
		(property "Device Type" "R402H16"
			(at 0.064008 -5.517896 0)
			(unlocked yes)
			(layer "F.Fab")
			(hide yes)
			(effects
				(font
					(size 1.016 1.016)
					(thickness 0.1524)
				)
			)
		)
		(duplicate_pad_numbers_are_jumpers no)
		(fp_line
			(start -0.508 -0.9398)
			(end -0.508 0.9398)
			(stroke
				(width 0.1524)
				(type default)
			)
			(layer "F.SilkS")
		)
		(fp_line
			(start 0.508 -0.9398)
			(end -0.508 -0.9398)
			(stroke
				(width 0.1524)
				(type default)
			)
			(layer "F.SilkS")
		)
		(fp_rect
			(start -0.508 0.9398)
			(end 0.508 -0.9398)
			(stroke
				(width 0)
				(type default)
			)
			(fill no)
			(layer "F.CrtYd")
		)
		(fp_rect
			(start -0.508 0.9398)
			(end 0.508 -0.9398)
			(stroke
				(width 0)
				(type default)
			)
			(fill no)
			(layer "F.Fab")
		)
		(pad "1" smd custom
			(at 0 -0.4445)
			(size 0.1397 0.1397)
			(layers "F.Cu" "F.Mask" "F.Paste")
			(net "P3V3_FB_R")
			(options
				(clearance outline)
				(anchor circle)
			)
			(primitives
				(gr_poly
					(pts
						(arc
							(start -0.1778 -0.2794)
							(mid -0.249642 -0.249642)
							(end -0.2794 -0.1778)
						)
						(arc
							(start -0.2794 0.1778)
							(mid -0.249642 0.249642)
							(end -0.1778 0.2794)
						)
						(arc
							(start 0.1778 0.2794)
							(mid 0.249642 0.249642)
							(end 0.2794 0.1778)
						)
						(arc
							(start 0.2794 -0.1778)
							(mid 0.249642 -0.249642)
							(end 0.1778 -0.2794)
						)
					)
					(width 0)
					(fill yes)
				)
			)
		)
		(pad "2" smd custom
			(at 0 0.4445)
			(size 0.1397 0.1397)
			(layers "F.Cu" "F.Mask" "F.Paste")
			(net "P3V3_FB")
			(options
				(clearance outline)
				(anchor circle)
			)
			(primitives
				(gr_poly
					(pts
						(arc
							(start -0.1778 -0.2794)
							(mid -0.249642 -0.249642)
							(end -0.2794 -0.1778)
						)
						(arc
							(start -0.2794 0.1778)
							(mid -0.249642 0.249642)
							(end -0.1778 0.2794)
						)
						(arc
							(start 0.1778 0.2794)
							(mid 0.249642 0.249642)
							(end 0.2794 0.1778)
						)
						(arc
							(start 0.2794 -0.1778)
							(mid 0.249642 -0.249642)
							(end 0.1778 -0.2794)
						)
					)
					(width 0)
					(fill yes)
				)
			)
		)
	)
	(footprint ""
		(layer "F.Cu")
		(at 13.715746 -481.8507 -90)
		(property "Reference" "PR37"
			(at 0 0 270)
			(layer "F.SilkS")
			(hide yes)
			(effects
				(font
					(size 1.27 1.27)
				)
			)
		)
		(property "Value" "10R2F-L-GP"
			(at 0.064008 -3.993896 270)
			(unlocked yes)
			(layer "F.Fab")
			(hide yes)
			(effects
				(font
					(size 1.016 1.016)
					(thickness 0.1524)
				)
			)
		)
		(property "Device Type" "R402H14"
			(at 0.064008 -5.517896 270)
			(unlocked yes)
			(layer "F.Fab")
			(hide yes)
			(effects
				(font
					(size 1.016 1.016)
					(thickness 0.1524)
				)
			)
		)
		(duplicate_pad_numbers_are_jumpers no)
		(fp_line
			(start -0.508 -0.9398)
			(end -0.508 0.9398)
			(stroke
				(width 0.1524)
				(type default)
			)
			(layer "F.SilkS")
		)
		(fp_line
			(start 0.508 -0.9398)
			(end -0.508 -0.9398)
			(stroke
				(width 0.1524)
				(type default)
			)
			(layer "F.SilkS")
		)
		(fp_rect
			(start -0.508 0.9398)
			(end 0.508 -0.9398)
			(stroke
				(width 0)
				(type default)
			)
			(fill no)
			(layer "F.CrtYd")
		)
		(fp_rect
			(start -0.508 0.9398)
			(end 0.508 -0.9398)
			(stroke
				(width 0)
				(type default)
			)
			(fill no)
			(layer "F.Fab")
		)
		(pad "1" smd custom
			(at 0 -0.4445 270)
			(size 0.1397 0.1397)
			(layers "F.Cu" "F.Mask" "F.Paste")
			(net "P5VC")
			(options
				(clearance outline)
				(anchor circle)
			)
			(primitives
				(gr_poly
					(pts
						(arc
							(start -0.1778 -0.2794)
							(mid -0.249642 -0.249642)
							(end -0.2794 -0.1778)
						)
						(arc
							(start -0.2794 0.1778)
							(mid -0.249642 0.249642)
							(end -0.1778 0.2794)
						)
						(arc
							(start 0.1778 0.2794)
							(mid 0.249642 0.249642)
							(end 0.2794 0.1778)
						)
						(arc
							(start 0.2794 -0.1778)
							(mid 0.249642 -0.249642)
							(end 0.1778 -0.2794)
						)
					)
					(width 0)
					(fill yes)
				)
			)
		)
		(pad "2" smd custom
			(at 0 0.4445 270)
			(size 0.1397 0.1397)
			(layers "F.Cu" "F.Mask" "F.Paste")
			(net "P5VC_VFB_NET")
			(options
				(clearance outline)
				(anchor circle)
			)
			(primitives
				(gr_poly
					(pts
						(arc
							(start -0.1778 -0.2794)
							(mid -0.249642 -0.249642)
							(end -0.2794 -0.1778)
						)
						(arc
							(start -0.2794 0.1778)
							(mid -0.249642 0.249642)
							(end -0.1778 0.2794)
						)
						(arc
							(start 0.1778 0.2794)
							(mid 0.249642 0.249642)
							(end 0.2794 0.1778)
						)
						(arc
							(start 0.2794 -0.1778)
							(mid 0.249642 -0.249642)
							(end 0.1778 -0.2794)
						)
					)
					(width 0)
					(fill yes)
				)
			)
		)
	)
	(footprint ""
		(layer "F.Cu")
		(at 84.200492 -85.626956 -90)
		(property "Reference" "R458"
			(at 0 0 270)
			(layer "F.SilkS")
			(hide yes)
			(effects
				(font
					(size 1.27 1.27)
				)
			)
		)
		(property "Value" "4K7R2J-2-GP"
			(at 0.064008 -3.993896 270)
			(unlocked yes)
			(layer "F.Fab")
			(hide yes)
			(effects
				(font
					(size 1.016 1.016)
					(thickness 0.1524)
				)
			)
		)
		(property "Device Type" "R402H16"
			(at 0.064008 -5.517896 270)
			(unlocked yes)
			(layer "F.Fab")
			(hide yes)
			(effects
				(font
					(size 1.016 1.016)
					(thickness 0.1524)
				)
			)
		)
		(duplicate_pad_numbers_are_jumpers no)
		(fp_line
			(start -0.508 -0.9398)
			(end -0.508 0.9398)
			(stroke
				(width 0.1524)
				(type default)
			)
			(layer "F.SilkS")
		)
		(fp_line
			(start 0.508 -0.9398)
			(end -0.508 -0.9398)
			(stroke
				(width 0.1524)
				(type default)
			)
			(layer "F.SilkS")
		)
		(fp_rect
			(start -0.508 0.9398)
			(end 0.508 -0.9398)
			(stroke
				(width 0)
				(type default)
			)
			(fill no)
			(layer "F.CrtYd")
		)
		(fp_rect
			(start -0.508 0.9398)
			(end 0.508 -0.9398)
			(stroke
				(width 0)
				(type default)
			)
			(fill no)
			(layer "F.Fab")
		)
		(pad "1" smd custom
			(at 0 -0.4445 270)
			(size 0.1397 0.1397)
			(layers "F.Cu" "F.Mask" "F.Paste")
			(net "P3V3")
			(options
				(clearance outline)
				(anchor circle)
			)
			(primitives
				(gr_poly
					(pts
						(arc
							(start -0.1778 -0.2794)
							(mid -0.249642 -0.249642)
							(end -0.2794 -0.1778)
						)
						(arc
							(start -0.2794 0.1778)
							(mid -0.249642 0.249642)
							(end -0.1778 0.2794)
						)
						(arc
							(start 0.1778 0.2794)
							(mid 0.249642 0.249642)
							(end 0.2794 0.1778)
						)
						(arc
							(start 0.2794 -0.1778)
							(mid 0.249642 -0.249642)
							(end 0.1778 -0.2794)
						)
					)
					(width 0)
					(fill yes)
				)
			)
		)
		(pad "2" smd custom
			(at 0 0.4445 270)
			(size 0.1397 0.1397)
			(layers "F.Cu" "F.Mask" "F.Paste")
			(net "SAS_EXP_A_PWR9")
			(options
				(clearance outline)
				(anchor circle)
			)
			(primitives
				(gr_poly
					(pts
						(arc
							(start -0.1778 -0.2794)
							(mid -0.249642 -0.249642)
							(end -0.2794 -0.1778)
						)
						(arc
							(start -0.2794 0.1778)
							(mid -0.249642 0.249642)
							(end -0.1778 0.2794)
						)
						(arc
							(start 0.1778 0.2794)
							(mid 0.249642 0.249642)
							(end 0.2794 0.1778)
						)
						(arc
							(start 0.2794 -0.1778)
							(mid 0.249642 -0.249642)
							(end 0.1778 -0.2794)
						)
					)
					(width 0)
					(fill yes)
				)
			)
		)
	)
)
